(kicad_pcb
	(version 20260206)
	(generator "pcbnew")
	(generator_version "10.0")
	(general
		(thickness 1.6)
		(legacy_teardrops no)
	)
	(paper "A4")
	(title_block
		(title "01162023_DA0F0TEBIF0_F0T_Expander_BD_F_brd_V02_OCP.brd")
		(comment 1 "Grand Teton / footprints 8537-8543 of 9728")
	)
	(layers
		(0 "F.Cu" signal "TOP")
		(4 "In1.Cu" signal "GND")
		(6 "In2.Cu" signal "VCC")
		(8 "In3.Cu" signal "VCC1")
		(10 "In4.Cu" signal "GND1")
		(12 "In5.Cu" signal "IN1")
		(14 "In6.Cu" signal "GND2")
		(16 "In7.Cu" signal "IN2")
		(18 "In8.Cu" signal "GND3")
		(20 "In9.Cu" signal "IN3")
		(22 "In10.Cu" signal "GND4")
		(24 "In11.Cu" signal "IN4")
		(26 "In12.Cu" signal "GND5")
		(28 "In13.Cu" signal "IN5")
		(30 "In14.Cu" signal "GND6")
		(32 "In15.Cu" signal "IN6")
		(34 "In16.Cu" signal "GND7")
		(2 "B.Cu" signal "BOTTOM")
		(9 "F.Adhes" user "F.Adhesive")
		(11 "B.Adhes" user "B.Adhesive")
		(13 "F.Paste" user "Package Geometry/Pastemask Top")
		(15 "B.Paste" user "Package Geometry/Pastemask Bottom")
		(5 "F.SilkS" user "Ref Des/Silkscreen Top")
		(7 "B.SilkS" user "Ref Des/Silkscreen Bottom")
		(1 "F.Mask" user "Board Geometry/Soldermask Top")
		(3 "B.Mask" user "Board Geometry/Soldermask Bottom")
		(17 "Dwgs.User" user "User.Drawings")
		(19 "Cmts.User" user "User.Comments")
		(21 "Eco1.User" user "User.Eco1")
		(23 "Eco2.User" user "User.Eco2")
		(25 "Edge.Cuts" user "Board Geometry/Outline")
		(27 "Margin" user)
		(31 "F.CrtYd" user "Package Geometry/Place Bound Top")
		(29 "B.CrtYd" user "Package Geometry/Place Bound Bottom")
		(35 "F.Fab" user "Ref Des/Assembly Top")
		(33 "B.Fab" user "Ref Des/Assembly Bottom")
	)
	(footprint ""
		(layer "B.Cu")
		(at 53.949854 -299.699934 -90)
		(property "Reference" "C1218"
			(at 0 0 90)
			(layer "B.SilkS")
			(hide yes)
			(effects
				(font
					(size 1.27 1.27)
				)
				(justify mirror)
			)
		)
		(property "Value" ""
			(at 0 0 90)
			(layer "B.Fab")
			(effects
				(font
					(size 1.27 1.27)
				)
				(justify mirror)
			)
		)
		(duplicate_pad_numbers_are_jumpers no)
		(fp_line
			(start -0.299974 0.150114)
			(end 0.299974 0.150114)
			(stroke
				(width 0.1)
				(type default)
			)
			(layer "B.Fab")
		)
		(fp_line
			(start 0.299974 0.150114)
			(end 0.299974 -0.150114)
			(stroke
				(width 0.1)
				(type default)
			)
			(layer "B.Fab")
		)
		(fp_line
			(start -0.299974 -0.150114)
			(end -0.299974 0.150114)
			(stroke
				(width 0.1)
				(type default)
			)
			(layer "B.Fab")
		)
		(fp_line
			(start 0.299974 -0.150114)
			(end -0.299974 -0.150114)
			(stroke
				(width 0.1)
				(type default)
			)
			(layer "B.Fab")
		)
		(pad "1" smd rect
			(at 0.2667 0 90)
			(size 0.3048 0.381)
			(layers "B.Cu" "B.Mask" "B.Paste")
			(net "P0V8_SERDES_VDDA_PEX0")
		)
		(pad "2" smd rect
			(at -0.2667 0 90)
			(size 0.3048 0.381)
			(layers "B.Cu" "B.Mask" "B.Paste")
			(net "GND")
		)
	)
	(footprint ""
		(layer "B.Cu")
		(at 344.49385 -218.787218 -90)
		(property "Reference" "C2063"
			(at 0 0 90)
			(layer "B.SilkS")
			(hide yes)
			(effects
				(font
					(size 1.27 1.27)
				)
				(justify mirror)
			)
		)
		(property "Value" ""
			(at 0 0 90)
			(layer "B.Fab")
			(effects
				(font
					(size 1.27 1.27)
				)
				(justify mirror)
			)
		)
		(duplicate_pad_numbers_are_jumpers no)
		(fp_line
			(start -0.69215 0.2921)
			(end 0.69215 0.2921)
			(stroke
				(width 0.1524)
				(type default)
			)
			(layer "B.SilkS")
		)
		(fp_line
			(start 0.69215 0.2921)
			(end 0.69215 -0.2921)
			(stroke
				(width 0.1524)
				(type default)
			)
			(layer "B.SilkS")
		)
		(fp_line
			(start -0.69215 -0.2921)
			(end -0.69215 0.2921)
			(stroke
				(width 0.1524)
				(type default)
			)
			(layer "B.SilkS")
		)
		(fp_line
			(start 0.69215 -0.2921)
			(end -0.69215 -0.2921)
			(stroke
				(width 0.1524)
				(type default)
			)
			(layer "B.SilkS")
		)
		(fp_line
			(start -0.51435 0.2794)
			(end 0.51435 0.2794)
			(stroke
				(width 0.1)
				(type default)
			)
			(layer "B.Fab")
		)
		(fp_line
			(start 0.51435 0.2794)
			(end 0.51435 -0.2794)
			(stroke
				(width 0.1)
				(type default)
			)
			(layer "B.Fab")
		)
		(fp_line
			(start -0.51435 -0.2794)
			(end -0.51435 0.2794)
			(stroke
				(width 0.1)
				(type default)
			)
			(layer "B.Fab")
		)
		(fp_line
			(start 0.51435 -0.2794)
			(end -0.51435 -0.2794)
			(stroke
				(width 0.1)
				(type default)
			)
			(layer "B.Fab")
		)
		(pad "1" smd circle
			(at 0.40005 0 90)
			(size 0 0)
			(layers "B.Cu" "B.Mask" "B.Paste")
			(net "P3V3_VCC_FPGA_CORE")
		)
		(pad "2" smd circle
			(at -0.40005 0 90)
			(size 0 0)
			(layers "B.Cu" "B.Mask" "B.Paste")
			(net "GND")
		)
		(zone
			(layer "B.Cu")
			(hatch none 0.5)
			(connect_pads
				(clearance 0)
			)
			(min_thickness 0.25)
			(keepout
				(tracks not_allowed)
				(vias allowed)
				(pads allowed)
				(copperpour not_allowed)
				(footprints allowed)
			)
			(placement
				(enabled no)
				(sheetname "")
			)
			(fill
				(thermal_gap 0.5)
				(thermal_bridge_width 0.5)
				(island_removal_mode 0)
			)
			(polygon
				(pts
					(xy 344.40622 -218.596718) (xy 344.348054 -218.688158) (xy 344.348054 -218.887548) (xy 344.40622 -218.977718)
					(xy 344.58148 -218.977718) (xy 344.6399 -218.887548) (xy 344.6399 -218.688158) (xy 344.581734 -218.596718)
				)
			)
		)
	)
	(footprint ""
		(layer "B.Cu")
		(at 191.823848 -289.724846 90)
		(property "Reference" "R934"
			(at 0 0 90)
			(layer "B.SilkS")
			(hide yes)
			(effects
				(font
					(size 1.27 1.27)
				)
				(justify mirror)
			)
		)
		(property "Value" ""
			(at 0 0 90)
			(layer "B.Fab")
			(effects
				(font
					(size 1.27 1.27)
				)
				(justify mirror)
			)
		)
		(duplicate_pad_numbers_are_jumpers no)
		(fp_line
			(start 0.7874 -0.4064)
			(end -0.7874 -0.4064)
			(stroke
				(width 0.1524)
				(type default)
			)
			(layer "B.SilkS")
		)
		(fp_line
			(start -0.7874 -0.4064)
			(end -0.7874 0.4064)
			(stroke
				(width 0.1524)
				(type default)
			)
			(layer "B.SilkS")
		)
		(fp_line
			(start 0.7874 0.4064)
			(end 0.7874 -0.4064)
			(stroke
				(width 0.1524)
				(type default)
			)
			(layer "B.SilkS")
		)
		(fp_line
			(start -0.7874 0.4064)
			(end 0.7874 0.4064)
			(stroke
				(width 0.1524)
				(type default)
			)
			(layer "B.SilkS")
		)
		(fp_line
			(start 0.67945 -0.305054)
			(end 0.12065 -0.305054)
			(stroke
				(width 0.1)
				(type default)
			)
			(layer "B.Fab")
		)
		(fp_line
			(start 0.12065 -0.305054)
			(end 0.12065 -0.2794)
			(stroke
				(width 0.1)
				(type default)
			)
			(layer "B.Fab")
		)
		(fp_line
			(start -0.12065 -0.3048)
			(end -0.67945 -0.3048)
			(stroke
				(width 0.1)
				(type default)
			)
			(layer "B.Fab")
		)
		(fp_line
			(start -0.67945 -0.3048)
			(end -0.67945 0.3048)
			(stroke
				(width 0.1)
				(type default)
			)
			(layer "B.Fab")
		)
		(fp_line
			(start 0.12065 -0.2794)
			(end -0.12065 -0.2794)
			(stroke
				(width 0.1)
				(type default)
			)
			(layer "B.Fab")
		)
		(fp_line
			(start -0.12065 -0.2794)
			(end -0.12065 -0.3048)
			(stroke
				(width 0.1)
				(type default)
			)
			(layer "B.Fab")
		)
		(fp_line
			(start 0.12065 0.2794)
			(end 0.12065 0.3048)
			(stroke
				(width 0.1)
				(type default)
			)
			(layer "B.Fab")
		)
		(fp_line
			(start -0.120396 0.2794)
			(end 0.12065 0.2794)
			(stroke
				(width 0.1)
				(type default)
			)
			(layer "B.Fab")
		)
		(fp_line
			(start 0.67945 0.3048)
			(end 0.67945 -0.305054)
			(stroke
				(width 0.1)
				(type default)
			)
			(layer "B.Fab")
		)
		(fp_line
			(start 0.12065 0.3048)
			(end 0.67945 0.3048)
			(stroke
				(width 0.1)
				(type default)
			)
			(layer "B.Fab")
		)
		(fp_line
			(start -0.120396 0.3048)
			(end -0.120396 0.2794)
			(stroke
				(width 0.1)
				(type default)
			)
			(layer "B.Fab")
		)
		(fp_line
			(start -0.67945 0.3048)
			(end -0.120396 0.3048)
			(stroke
				(width 0.1)
				(type default)
			)
			(layer "B.Fab")
		)
		(pad "1" smd circle
			(at 0.40005 0 270)
			(size 0 0)
			(layers "B.Cu" "B.Mask" "B.Paste")
			(net "UART_PEX1_SDB_TX")
		)
		(pad "2" smd circle
			(at -0.40005 0 270)
			(size 0 0)
			(layers "B.Cu" "B.Mask" "B.Paste")
			(net "UART_PEX1_SDB_R_TX")
		)
	)
	(footprint ""
		(layer "B.Cu")
		(at 52.999894 -303.499774 -90)
		(property "Reference" "C2915"
			(at 0 0 90)
			(layer "B.SilkS")
			(hide yes)
			(effects
				(font
					(size 1.27 1.27)
				)
				(justify mirror)
			)
		)
		(property "Value" ""
			(at 0 0 90)
			(layer "B.Fab")
			(effects
				(font
					(size 1.27 1.27)
				)
				(justify mirror)
			)
		)
		(duplicate_pad_numbers_are_jumpers no)
		(fp_line
			(start -0.299974 0.150114)
			(end 0.299974 0.150114)
			(stroke
				(width 0.1)
				(type default)
			)
			(layer "B.Fab")
		)
		(fp_line
			(start 0.299974 0.150114)
			(end 0.299974 -0.150114)
			(stroke
				(width 0.1)
				(type default)
			)
			(layer "B.Fab")
		)
		(fp_line
			(start -0.299974 -0.150114)
			(end -0.299974 0.150114)
			(stroke
				(width 0.1)
				(type default)
			)
			(layer "B.Fab")
		)
		(fp_line
			(start 0.299974 -0.150114)
			(end -0.299974 -0.150114)
			(stroke
				(width 0.1)
				(type default)
			)
			(layer "B.Fab")
		)
		(pad "1" smd rect
			(at 0.2667 0 90)
			(size 0.3048 0.381)
			(layers "B.Cu" "B.Mask" "B.Paste")
			(net "P1V25_PEX0")
		)
		(pad "2" smd rect
			(at -0.2667 0 90)
			(size 0.3048 0.381)
			(layers "B.Cu" "B.Mask" "B.Paste")
			(net "GND")
		)
	)
	(footprint ""
		(layer "B.Cu")
		(at 442.553344 20.568412)
		(property "Reference" "DE05F_3"
			(at 2.403856 3.054858 0)
			(unlocked yes)
			(layer "B.SilkS")
			(effects
				(font
					(size 0.7874 0.5842)
					(thickness 0.1524)
				)
				(justify left mirror)
			)
		)
		(property "Value" ""
			(at 0 0 0)
			(layer "B.Fab")
			(effects
				(font
					(size 1.27 1.27)
				)
				(justify mirror)
			)
		)
		(duplicate_pad_numbers_are_jumpers no)
		(fp_line
			(start -1.2192 -2.1082)
			(end -1.2192 2.1082)
			(stroke
				(width 0.1524)
				(type default)
			)
			(layer "B.SilkS")
		)
		(fp_line
			(start -1.2192 2.1082)
			(end 1.2192 2.1082)
			(stroke
				(width 0.1524)
				(type default)
			)
			(layer "B.SilkS")
		)
		(fp_line
			(start 1.2192 -2.1082)
			(end -1.2192 -2.1082)
			(stroke
				(width 0.1524)
				(type default)
			)
			(layer "B.SilkS")
		)
		(fp_line
			(start 1.2192 2.1082)
			(end 1.2192 -2.1082)
			(stroke
				(width 0.1524)
				(type default)
			)
			(layer "B.SilkS")
		)
		(pad "" np_thru_hole circle
			(at -3.4671 -1.27 270)
			(size 1.0414 1.0414)
			(drill 1.0414)
			(layers "*.Cu" "*.Mask")
			(clearance 0.381)
			(thermal_gap 0.381)
		)
		(pad "" np_thru_hole circle
			(at -3.4671 1.27 270)
			(size 1.0414 1.0414)
			(drill 1.0414)
			(layers "*.Cu" "*.Mask")
			(clearance 0.381)
			(thermal_gap 0.381)
		)
		(pad "" np_thru_hole circle
			(at 2.8829 -1.27 270)
			(size 1.0414 1.0414)
			(drill 1.0414)
			(layers "*.Cu" "*.Mask")
			(clearance 0.381)
			(thermal_gap 0.381)
		)
		(pad "" np_thru_hole circle
			(at 2.8829 1.27 270)
			(size 1.0414 1.0414)
			(drill 1.0414)
			(layers "*.Cu" "*.Mask")
			(clearance 0.381)
			(thermal_gap 0.381)
		)
		(pad "1" smd rect
			(at -0.8255 -0.249936 270)
			(size 0.3048 0.508)
			(layers "B.Cu" "B.Mask" "B.Paste")
			(net "85_5INCH_IN5_DP")
		)
		(pad "2" smd rect
			(at -0.8255 0.249936 270)
			(size 0.3048 0.508)
			(layers "B.Cu" "B.Mask" "B.Paste")
			(net "85_5INCH_IN5_DN")
		)
		(pad "3" smd circle
			(at 0 0 180)
			(size 0 0)
			(layers "B.Cu" "B.Mask" "B.Paste")
			(net "COUPON_GND2")
		)
		(zone
			(layers "F.Cu" "B.Cu" "In1.Cu" "In2.Cu" "In3.Cu" "In4.Cu" "In5.Cu" "In6.Cu"
				"In7.Cu" "In8.Cu" "In9.Cu" "In10.Cu" "In11.Cu" "In12.Cu" "In13.Cu" "In14.Cu"
				"In15.Cu" "In16.Cu"
			)
			(hatch none 0.5)
			(connect_pads
				(clearance 0)
			)
			(min_thickness 0.25)
			(keepout
				(tracks not_allowed)
				(vias allowed)
				(pads allowed)
				(copperpour not_allowed)
				(footprints allowed)
			)
			(placement
				(enabled no)
				(sheetname "")
			)
			(fill
				(thermal_gap 0.5)
				(thermal_bridge_width 0.5)
				(island_removal_mode 0)
			)
			(polygon
				(pts
					(arc
						(start 440.013344 19.298412)
						(mid 438.159144 19.298412)
						(end 440.013344 19.298412)
					)
				)
			)
		)
		(zone
			(layers "F.Cu" "B.Cu" "In1.Cu" "In2.Cu" "In3.Cu" "In4.Cu" "In5.Cu" "In6.Cu"
				"In7.Cu" "In8.Cu" "In9.Cu" "In10.Cu" "In11.Cu" "In12.Cu" "In13.Cu" "In14.Cu"
				"In15.Cu" "In16.Cu"
			)
			(hatch none 0.5)
			(connect_pads
				(clearance 0)
			)
			(min_thickness 0.25)
			(keepout
				(tracks not_allowed)
				(vias allowed)
				(pads allowed)
				(copperpour not_allowed)
				(footprints allowed)
			)
			(placement
				(enabled no)
				(sheetname "")
			)
			(fill
				(thermal_gap 0.5)
				(thermal_bridge_width 0.5)
				(island_removal_mode 0)
			)
			(polygon
				(pts
					(arc
						(start 440.013344 21.838412)
						(mid 438.159144 21.838412)
						(end 440.013344 21.838412)
					)
				)
			)
		)
		(zone
			(layers "F.Cu" "B.Cu" "In1.Cu" "In2.Cu" "In3.Cu" "In4.Cu" "In5.Cu" "In6.Cu"
				"In7.Cu" "In8.Cu" "In9.Cu" "In10.Cu" "In11.Cu" "In12.Cu" "In13.Cu" "In14.Cu"
				"In15.Cu" "In16.Cu"
			)
			(hatch none 0.5)
			(connect_pads
				(clearance 0)
			)
			(min_thickness 0.25)
			(keepout
				(tracks not_allowed)
				(vias allowed)
				(pads allowed)
				(copperpour not_allowed)
				(footprints allowed)
			)
			(placement
				(enabled no)
				(sheetname "")
			)
			(fill
				(thermal_gap 0.5)
				(thermal_bridge_width 0.5)
				(island_removal_mode 0)
			)
			(polygon
				(pts
					(arc
						(start 446.363344 19.298412)
						(mid 444.509144 19.298412)
						(end 446.363344 19.298412)
					)
				)
			)
		)
		(zone
			(layers "F.Cu" "B.Cu" "In1.Cu" "In2.Cu" "In3.Cu" "In4.Cu" "In5.Cu" "In6.Cu"
				"In7.Cu" "In8.Cu" "In9.Cu" "In10.Cu" "In11.Cu" "In12.Cu" "In13.Cu" "In14.Cu"
				"In15.Cu" "In16.Cu"
			)
			(hatch none 0.5)
			(connect_pads
				(clearance 0)
			)
			(min_thickness 0.25)
			(keepout
				(tracks not_allowed)
				(vias allowed)
				(pads allowed)
				(copperpour not_allowed)
				(footprints allowed)
			)
			(placement
				(enabled no)
				(sheetname "")
			)
			(fill
				(thermal_gap 0.5)
				(thermal_bridge_width 0.5)
				(island_removal_mode 0)
			)
			(polygon
				(pts
					(arc
						(start 446.363344 21.838412)
						(mid 444.509144 21.838412)
						(end 446.363344 21.838412)
					)
				)
			)
		)
		(zone
			(layer "B.Cu")
			(hatch none 0.5)
			(connect_pads
				(clearance 0)
			)
			(min_thickness 0.25)
			(keepout
				(tracks not_allowed)
				(vias allowed)
				(pads allowed)
				(copperpour not_allowed)
				(footprints allowed)
			)
			(placement
				(enabled no)
				(sheetname "")
			)
			(fill
				(thermal_gap 0.5)
				(thermal_bridge_width 0.5)
				(island_removal_mode 0)
			)
			(polygon
				(pts
					(xy 441.435744 20.019772) (xy 441.435744 20.115276) (xy 442.032644 20.115276) (xy 442.032644 20.521676)
					(xy 441.435744 20.521676) (xy 441.435744 20.615148) (xy 442.032644 20.615148) (xy 442.032644 21.021548)
					(xy 441.435744 21.021548) (xy 441.435744 21.117052) (xy 442.134244 21.117052) (xy 442.134244 20.019772)
				)
			)
		)
	)
	(footprint ""
		(layer "B.Cu")
		(at 182.87492 -286.399732 90)
		(property "Reference" "C3158"
			(at 0 0 90)
			(layer "B.SilkS")
			(hide yes)
			(effects
				(font
					(size 1.27 1.27)
				)
				(justify mirror)
			)
		)
		(property "Value" ""
			(at 0 0 90)
			(layer "B.Fab")
			(effects
				(font
					(size 1.27 1.27)
				)
				(justify mirror)
			)
		)
		(duplicate_pad_numbers_are_jumpers no)
		(fp_line
			(start 0.299974 -0.150114)
			(end -0.299974 -0.150114)
			(stroke
				(width 0.1)
				(type default)
			)
			(layer "B.Fab")
		)
		(fp_line
			(start -0.299974 -0.150114)
			(end -0.299974 0.150114)
			(stroke
				(width 0.1)
				(type default)
			)
			(layer "B.Fab")
		)
		(fp_line
			(start 0.299974 0.150114)
			(end 0.299974 -0.150114)
			(stroke
				(width 0.1)
				(type default)
			)
			(layer "B.Fab")
		)
		(fp_line
			(start -0.299974 0.150114)
			(end 0.299974 0.150114)
			(stroke
				(width 0.1)
				(type default)
			)
			(layer "B.Fab")
		)
		(pad "1" smd rect
			(at 0.2667 0 270)
			(size 0.3048 0.381)
			(layers "B.Cu" "B.Mask" "B.Paste")
			(net "P1V25_SERDES_VDDPLL_PEX1")
		)
		(pad "2" smd rect
			(at -0.2667 0 270)
			(size 0.3048 0.381)
			(layers "B.Cu" "B.Mask" "B.Paste")
			(net "GND")
		)
	)
	(footprint ""
		(layer "B.Cu")
		(at 177.42027 -198.287386 180)
		(property "Reference" "R1029"
			(at 0 0 0)
			(layer "B.SilkS")
			(hide yes)
			(effects
				(font
					(size 1.27 1.27)
				)
				(justify mirror)
			)
		)
		(property "Value" ""
			(at 0 0 0)
			(layer "B.Fab")
			(effects
				(font
					(size 1.27 1.27)
				)
				(justify mirror)
			)
		)
		(duplicate_pad_numbers_are_jumpers no)
		(fp_line
			(start 0.7874 0.4064)
			(end 0.7874 -0.4064)
			(stroke
				(width 0.1524)
				(type default)
			)
			(layer "B.SilkS")
		)
		(fp_line
			(start 0.7874 -0.4064)
			(end -0.7874 -0.4064)
			(stroke
				(width 0.1524)
				(type default)
			)
			(layer "B.SilkS")
		)
		(fp_line
			(start -0.7874 0.4064)
			(end 0.7874 0.4064)
			(stroke
				(width 0.1524)
				(type default)
			)
			(layer "B.SilkS")
		)
		(fp_line
			(start -0.7874 -0.4064)
			(end -0.7874 0.4064)
			(stroke
				(width 0.1524)
				(type default)
			)
			(layer "B.SilkS")
		)
		(fp_line
			(start 0.67945 0.3048)
			(end 0.67945 -0.305054)
			(stroke
				(width 0.1)
				(type default)
			)
			(layer "B.Fab")
		)
		(fp_line
			(start 0.67945 -0.305054)
			(end 0.12065 -0.305054)
			(stroke
				(width 0.1)
				(type default)
			)
			(layer "B.Fab")
		)
		(fp_line
			(start 0.12065 0.3048)
			(end 0.67945 0.3048)
			(stroke
				(width 0.1)
				(type default)
			)
			(layer "B.Fab")
		)
		(fp_line
			(start 0.12065 0.2794)
			(end 0.12065 0.3048)
			(stroke
				(width 0.1)
				(type default)
			)
			(layer "B.Fab")
		)
		(fp_line
			(start 0.12065 -0.2794)
			(end -0.12065 -0.2794)
			(stroke
				(width 0.1)
				(type default)
			)
			(layer "B.Fab")
		)
		(fp_line
			(start 0.12065 -0.305054)
			(end 0.12065 -0.2794)
			(stroke
				(width 0.1)
				(type default)
			)
			(layer "B.Fab")
		)
		(fp_line
			(start -0.120396 0.3048)
			(end -0.120396 0.2794)
			(stroke
				(width 0.1)
				(type default)
			)
			(layer "B.Fab")
		)
		(fp_line
			(start -0.120396 0.2794)
			(end 0.12065 0.2794)
			(stroke
				(width 0.1)
				(type default)
			)
			(layer "B.Fab")
		)
		(fp_line
			(start -0.12065 -0.2794)
			(end -0.12065 -0.3048)
			(stroke
				(width 0.1)
				(type default)
			)
			(layer "B.Fab")
		)
		(fp_line
			(start -0.12065 -0.3048)
			(end -0.67945 -0.3048)
			(stroke
				(width 0.1)
				(type default)
			)
			(layer "B.Fab")
		)
		(fp_line
			(start -0.67945 0.3048)
			(end -0.120396 0.3048)
			(stroke
				(width 0.1)
				(type default)
			)
			(layer "B.Fab")
		)
		(fp_line
			(start -0.67945 -0.3048)
			(end -0.67945 0.3048)
			(stroke
				(width 0.1)
				(type default)
			)
			(layer "B.Fab")
		)
		(pad "1" smd circle
			(at 0.40005 0)
			(size 0 0)
			(layers "B.Cu" "B.Mask" "B.Paste")
			(net "SPI_BIC1_CS0_LS01_N_DIR1")
		)
		(pad "2" smd circle
			(at -0.40005 0)
			(size 0 0)
			(layers "B.Cu" "B.Mask" "B.Paste")
			(net "P1V8_PEX")
		)
	)
)
